# S9S_MB_2U (Grand Teton) — schematic netlist excerpt (pin names and nets, part order shuffled) for the footprints in the layout excerpt that follows; sources: Cadence DE-HDL packaged netlist, KiCad conversion of 03242023_DA0F0TMBIJ0_F0T_Motherboard_J_brd_V01_OCP.brd

Q150  MOSFET_NCH_DUAL  PJT138K IC  pkg SOT363XD  page 255
  S1  = GND
  G1  = P12V_SCM_FAULT_R_N
  D2  = LED_P12V_SCM_FAULT_D2
  S2  = GND
  G2  = LED_P12V_SCM_FAULT_D1
  D1  = LED_P12V_SCM_FAULT_D1

JP15  CONN3_210HP1030BR1  CONN3_210-HP1-030BR1 IO  pkg HEADER1X3XG  page 215
  \1\  = PU_FORCE_PWRON
  \2\  = FM_FORCE_PWRON_LVC3
  \3\  = PD_FORCE_PWRON

(kicad_pcb
	(version 20260206)
	(generator "pcbnew")
	(generator_version "10.0")
	(general
		(thickness 1.6)
		(legacy_teardrops no)
	)
	(paper "A4")
	(title_block
		(title "03242023_DA0F0TMBIJ0_F0T_Motherboard_J_brd_V01_OCP.brd")
		(comment 1 "Grand Teton / footprints 4139-4140 of 6105")
	)
	(layers
		(0 "F.Cu" signal "TOP")
		(4 "In1.Cu" signal "GND")
		(6 "In2.Cu" signal "IN1")
		(8 "In3.Cu" signal "GND1")
		(10 "In4.Cu" signal "IN2")
		(12 "In5.Cu" signal "GND2")
		(14 "In6.Cu" signal "IN3")
		(16 "In7.Cu" signal "GND3")
		(18 "In8.Cu" signal "VCC")
		(20 "In9.Cu" signal "VCC1")
		(22 "In10.Cu" signal "GND4")
		(24 "In11.Cu" signal "IN4")
		(26 "In12.Cu" signal "GND5")
		(28 "In13.Cu" signal "IN5")
		(30 "In14.Cu" signal "GND6")
		(32 "In15.Cu" signal "IN6")
		(34 "In16.Cu" signal "GND7")
		(2 "B.Cu" signal "BOTTOM")
		(9 "F.Adhes" user "F.Adhesive")
		(11 "B.Adhes" user "B.Adhesive")
		(13 "F.Paste" user "Package Geometry/Pastemask Top")
		(15 "B.Paste" user "Package Geometry/Pastemask Bottom")
		(5 "F.SilkS" user "Ref Des/Silkscreen Top")
		(7 "B.SilkS" user "Ref Des/Silkscreen Bottom")
		(1 "F.Mask" user "Board Geometry/Soldermask Top")
		(3 "B.Mask" user "Board Geometry/Soldermask Bottom")
		(17 "Dwgs.User" user "User.Drawings")
		(19 "Cmts.User" user "User.Comments")
		(21 "Eco1.User" user "User.Eco1")
		(23 "Eco2.User" user "User.Eco2")
		(25 "Edge.Cuts" user "Board Geometry/Outline")
		(27 "Margin" user)
		(31 "F.CrtYd" user "Package Geometry/Place Bound Top")
		(29 "B.CrtYd" user "Package Geometry/Place Bound Bottom")
		(35 "F.Fab" user "Ref Des/Assembly Top")
		(33 "B.Fab" user "Ref Des/Assembly Bottom")
	)
	(footprint ""
		(layer "F.Cu")
		(at 126.635002 -154.195018 90)
		(property "Reference" "JP15"
			(at 9.14146 0.288798 0)
			(unlocked yes)
			(layer "F.SilkS")
			(effects
				(font
					(size 0.7874 0.5842)
					(thickness 0.1524)
				)
				(justify left)
			)
		)
		(property "Value" ""
			(at 0 0 90)
			(layer "F.Fab")
			(effects
				(font
					(size 1.27 1.27)
				)
			)
		)
		(duplicate_pad_numbers_are_jumpers no)
		(fp_line
			(start 1.249934 -1.320038)
			(end 1.249934 6.400038)
			(stroke
				(width 0.1524)
				(type default)
			)
			(layer "F.SilkS")
		)
		(fp_line
			(start -1.249934 -1.320038)
			(end 1.249934 -1.320038)
			(stroke
				(width 0.1524)
				(type default)
			)
			(layer "F.SilkS")
		)
		(fp_line
			(start 1.249934 6.400038)
			(end -1.249934 6.400038)
			(stroke
				(width 0.1524)
				(type default)
			)
			(layer "F.SilkS")
		)
		(fp_line
			(start -1.249934 6.400038)
			(end -1.249934 -1.320038)
			(stroke
				(width 0.1524)
				(type default)
			)
			(layer "F.SilkS")
		)
		(fp_poly
			(pts
				(xy -2.5654 -0.556514) (xy -1.452372 0) (xy -2.5654 0.556514)
			)
			(stroke
				(width 0)
				(type default)
			)
			(fill yes)
			(layer "F.SilkS")
		)
		(fp_line
			(start 1.249934 -1.320038)
			(end 1.249934 6.400038)
			(stroke
				(width 0.1)
				(type default)
			)
			(layer "F.Fab")
		)
		(fp_line
			(start -1.249934 -1.320038)
			(end 1.249934 -1.320038)
			(stroke
				(width 0.1)
				(type default)
			)
			(layer "F.Fab")
		)
		(fp_line
			(start 1.249934 6.400038)
			(end -1.249934 6.400038)
			(stroke
				(width 0.1)
				(type default)
			)
			(layer "F.Fab")
		)
		(fp_line
			(start -1.249934 6.400038)
			(end -1.249934 -1.320038)
			(stroke
				(width 0.1)
				(type default)
			)
			(layer "F.Fab")
		)
		(fp_poly
			(pts
				(xy -2.5654 -0.556514) (xy -1.452372 0) (xy -2.5654 0.556514)
			)
			(stroke
				(width 0)
				(type default)
			)
			(fill yes)
			(layer "F.Fab")
		)
		(fp_text user "3"
			(at -1.778 5.13207 90)
			(unlocked yes)
			(layer "F.SilkS")
			(effects
				(font
					(size 0.7874 0.5842)
					(thickness 0.1524)
				)
			)
		)
		(fp_text user "1"
			(at -1.143 0.02667 90)
			(unlocked yes)
			(layer "B.SilkS")
			(effects
				(font
					(size 0.7874 0.5842)
					(thickness 0.1524)
				)
				(justify mirror)
			)
		)
		(fp_text user "3"
			(at -1.1557 5.18287 90)
			(unlocked yes)
			(layer "B.SilkS")
			(effects
				(font
					(size 0.7874 0.5842)
					(thickness 0.1524)
				)
				(justify mirror)
			)
		)
		(fp_text user "1"
			(at -1.143 0.02667 90)
			(unlocked yes)
			(layer "B.Fab")
			(effects
				(font
					(size 0.7874 0.5842)
					(thickness 0.1524)
				)
				(justify mirror)
			)
		)
		(fp_text user "3"
			(at -1.1557 5.18287 90)
			(unlocked yes)
			(layer "B.Fab")
			(effects
				(font
					(size 0.7874 0.5842)
					(thickness 0.1524)
				)
				(justify mirror)
			)
		)
		(fp_text user "3"
			(at -1.778 5.13207 90)
			(unlocked yes)
			(layer "F.Fab")
			(effects
				(font
					(size 0.7874 0.5842)
					(thickness 0.1524)
				)
			)
		)
		(pad "1" thru_hole rect
			(at 0 0 90)
			(size 1.5494 1.5494)
			(drill 1.0414)
			(layers "*.Cu" "*.Mask")
			(remove_unused_layers no)
			(net "PU_FORCE_PWRON")
			(clearance 0)
			(padstack
				(mode front_inner_back)
				(layer "Inner"
					(shape circle)
					(size 1.5494 1.5494)
					(clearance 0)
				)
				(layer "B.Cu"
					(shape rect)
					(size 1.5494 1.5494)
					(clearance 0)
				)
			)
		)
		(pad "2" thru_hole circle
			(at 0 2.54 90)
			(size 1.5494 1.5494)
			(drill 1.0414)
			(layers "*.Cu" "*.Mask")
			(remove_unused_layers no)
			(net "FM_FORCE_PWRON_LVC3")
			(clearance 0)
		)
		(pad "3" thru_hole circle
			(at 0 5.08 90)
			(size 1.5494 1.5494)
			(drill 1.0414)
			(layers "*.Cu" "*.Mask")
			(remove_unused_layers no)
			(net "PD_FORCE_PWRON")
			(clearance 0)
		)
	)
	(footprint ""
		(layer "F.Cu")
		(at 209.149696 -67.853306)
		(property "Reference" "Q150"
			(at -1.4478 2.016252 0)
			(unlocked yes)
			(layer "F.SilkS")
			(effects
				(font
					(size 0.7874 0.5842)
					(thickness 0.1524)
				)
				(justify left)
			)
		)
		(property "Value" ""
			(at 0 0 0)
			(layer "F.Fab")
			(effects
				(font
					(size 1.27 1.27)
				)
			)
		)
		(duplicate_pad_numbers_are_jumpers no)
		(fp_line
			(start -1.332738 -1.100074)
			(end -0.4826 -1.100074)
			(stroke
				(width 0.1524)
				(type default)
			)
			(layer "F.SilkS")
		)
		(fp_line
			(start -1.332738 1.100074)
			(end -1.332738 -1.100074)
			(stroke
				(width 0.1524)
				(type default)
			)
			(layer "F.SilkS")
		)
		(fp_line
			(start -0.4826 -1.100074)
			(end 0 -0.541274)
			(stroke
				(width 0.1524)
				(type default)
			)
			(layer "F.SilkS")
		)
		(fp_line
			(start 0 -0.541274)
			(end 0.4826 -1.100074)
			(stroke
				(width 0.1524)
				(type default)
			)
			(layer "F.SilkS")
		)
		(fp_line
			(start 0.4826 -1.100074)
			(end 1.332738 -1.100074)
			(stroke
				(width 0.1524)
				(type default)
			)
			(layer "F.SilkS")
		)
		(fp_line
			(start 1.332738 -1.100074)
			(end 1.332738 1.100074)
			(stroke
				(width 0.1524)
				(type default)
			)
			(layer "F.SilkS")
		)
		(fp_line
			(start 1.332738 1.100074)
			(end -1.332738 1.100074)
			(stroke
				(width 0.1524)
				(type default)
			)
			(layer "F.SilkS")
		)
		(fp_poly
			(pts
				(xy -2.2352 -0.298958) (xy -2.2352 -1.001014) (xy -1.533144 -0.649986)
			)
			(stroke
				(width 0)
				(type default)
			)
			(fill yes)
			(layer "F.SilkS")
		)
		(fp_line
			(start -0.674878 -1.100074)
			(end 0.674878 -1.100074)
			(stroke
				(width 0.1)
				(type default)
			)
			(layer "F.Fab")
		)
		(fp_line
			(start -0.674878 1.100074)
			(end -0.674878 -1.100074)
			(stroke
				(width 0.1)
				(type default)
			)
			(layer "F.Fab")
		)
		(fp_line
			(start 0.674878 -1.100074)
			(end 0.674878 1.100074)
			(stroke
				(width 0.1)
				(type default)
			)
			(layer "F.Fab")
		)
		(fp_line
			(start 0.674878 1.100074)
			(end -0.674878 1.100074)
			(stroke
				(width 0.1)
				(type default)
			)
			(layer "F.Fab")
		)
		(fp_poly
			(pts
				(xy -2.2352 -0.298958) (xy -2.2352 -1.001014) (xy -1.533144 -0.649986)
			)
			(stroke
				(width 0)
				(type default)
			)
			(fill yes)
			(layer "F.Fab")
		)
		(pad "1" smd rect
			(at -0.94996 -0.649986 90)
			(size 0.4318 0.508)
			(layers "F.Cu" "F.Mask" "F.Paste")
			(net "GND")
		)
		(pad "2" smd rect
			(at -0.94996 0 90)
			(size 0.4318 0.508)
			(layers "F.Cu" "F.Mask" "F.Paste")
			(net "P12V_SCM_FAULT_R_N")
		)
		(pad "3" smd rect
			(at -0.94996 0.649986 90)
			(size 0.4318 0.508)
			(layers "F.Cu" "F.Mask" "F.Paste")
			(net "LED_P12V_SCM_FAULT_D2")
		)
		(pad "4" smd rect
			(at 0.94996 0.649986 90)
			(size 0.4318 0.508)
			(layers "F.Cu" "F.Mask" "F.Paste")
			(net "GND")
		)
		(pad "5" smd rect
			(at 0.94996 0 90)
			(size 0.4318 0.508)
			(layers "F.Cu" "F.Mask" "F.Paste")
			(net "LED_P12V_SCM_FAULT_D1")
		)
		(pad "6" smd rect
			(at 0.94996 -0.649986 90)
			(size 0.4318 0.508)
			(layers "F.Cu" "F.Mask" "F.Paste")
			(net "LED_P12V_SCM_FAULT_D1")
		)
	)
)
